# T6G (Grand Teton) — schematic netlist excerpt (pin names and nets, part order shuffled) for the footprints in the layout excerpt that follows; sources: Cadence DE-HDL packaged netlist, KiCad conversion of 04192023_DAF0TMB3IC0_F0TG_MB_C_brd_V02_OCP.brd

C2516  Q_CAP  22UF 4V 20% X6S  pkg C0402  page 71 : A = PVDD18_S5_P0 ; B = GND
C1172  Q_CAP  0.1UF 16V 10% X7R  pkg C0402  page 83 : A = P3V3_AUX ; B = GND
PC120_3  Q_CAP  22UF 16V 20% X6S  pkg C0805  page 202 : A = SW_P12V_AUX_PVDDCR_CPU1_P0_FLT ; B = GND

(kicad_pcb
	(version 20260206)
	(generator "pcbnew")
	(generator_version "10.0")
	(general
		(thickness 1.6)
		(legacy_teardrops no)
	)
	(paper "A4")
	(title_block
		(title "04192023_DAF0TMB3IC0_F0TG_MB_C_brd_V02_OCP.brd")
		(comment 1 "Grand Teton / footprints 5096-5098 of 8354")
	)
	(layers
		(0 "F.Cu" signal "TOP")
		(4 "In1.Cu" signal "GND")
		(6 "In2.Cu" signal "IN1")
		(8 "In3.Cu" signal "GND1")
		(10 "In4.Cu" signal "IN2")
		(12 "In5.Cu" signal "GND2")
		(14 "In6.Cu" signal "IN3")
		(16 "In7.Cu" signal "GND3")
		(18 "In8.Cu" signal "VCC")
		(20 "In9.Cu" signal "VCC1")
		(22 "In10.Cu" signal "GND4")
		(24 "In11.Cu" signal "IN4")
		(26 "In12.Cu" signal "GND5")
		(28 "In13.Cu" signal "IN5")
		(30 "In14.Cu" signal "GND6")
		(32 "In15.Cu" signal "IN6")
		(34 "In16.Cu" signal "GND7")
		(2 "B.Cu" signal "BOTTOM")
		(9 "F.Adhes" user "F.Adhesive")
		(11 "B.Adhes" user "B.Adhesive")
		(13 "F.Paste" user "Package Geometry/Pastemask Top")
		(15 "B.Paste" user "Package Geometry/Pastemask Bottom")
		(5 "F.SilkS" user "Ref Des/Silkscreen Top")
		(7 "B.SilkS" user "Ref Des/Silkscreen Bottom")
		(1 "F.Mask" user "Board Geometry/Soldermask Top")
		(3 "B.Mask" user "Board Geometry/Soldermask Bottom")
		(17 "Dwgs.User" user "User.Drawings")
		(19 "Cmts.User" user "User.Comments")
		(21 "Eco1.User" user "User.Eco1")
		(23 "Eco2.User" user "User.Eco2")
		(25 "Edge.Cuts" user "Board Geometry/Outline")
		(27 "Margin" user)
		(31 "F.CrtYd" user "Package Geometry/Place Bound Top")
		(29 "B.CrtYd" user "Package Geometry/Place Bound Bottom")
		(35 "F.Fab" user "Ref Des/Assembly Top")
		(33 "B.Fab" user "Ref Des/Assembly Bottom")
	)
	(footprint ""
		(layer "B.Cu")
		(at 347.008958 -252.54331 180)
		(property "Reference" "C2516"
			(at 0 0 0)
			(layer "B.SilkS")
			(hide yes)
			(effects
				(font
					(size 1.27 1.27)
				)
				(justify mirror)
			)
		)
		(property "Value" ""
			(at 0 0 0)
			(layer "B.Fab")
			(effects
				(font
					(size 1.27 1.27)
				)
				(justify mirror)
			)
		)
		(duplicate_pad_numbers_are_jumpers no)
		(fp_line
			(start 0.7874 0.4064)
			(end 0.7874 -0.4064)
			(stroke
				(width 0.1524)
				(type default)
			)
			(layer "B.SilkS")
		)
		(fp_line
			(start 0.7874 -0.4064)
			(end -0.7874 -0.4064)
			(stroke
				(width 0.1524)
				(type default)
			)
			(layer "B.SilkS")
		)
		(fp_line
			(start -0.7874 0.4064)
			(end 0.7874 0.4064)
			(stroke
				(width 0.1524)
				(type default)
			)
			(layer "B.SilkS")
		)
		(fp_line
			(start -0.7874 -0.4064)
			(end -0.7874 0.4064)
			(stroke
				(width 0.1524)
				(type default)
			)
			(layer "B.SilkS")
		)
		(fp_line
			(start 0.67945 0.3048)
			(end 0.67945 -0.305054)
			(stroke
				(width 0.1)
				(type default)
			)
			(layer "B.Fab")
		)
		(fp_line
			(start 0.67945 -0.305054)
			(end 0.12065 -0.305054)
			(stroke
				(width 0.1)
				(type default)
			)
			(layer "B.Fab")
		)
		(fp_line
			(start 0.12065 0.3048)
			(end 0.67945 0.3048)
			(stroke
				(width 0.1)
				(type default)
			)
			(layer "B.Fab")
		)
		(fp_line
			(start 0.12065 0.2794)
			(end 0.12065 0.3048)
			(stroke
				(width 0.1)
				(type default)
			)
			(layer "B.Fab")
		)
		(fp_line
			(start 0.12065 -0.2794)
			(end -0.12065 -0.2794)
			(stroke
				(width 0.1)
				(type default)
			)
			(layer "B.Fab")
		)
		(fp_line
			(start 0.12065 -0.305054)
			(end 0.12065 -0.2794)
			(stroke
				(width 0.1)
				(type default)
			)
			(layer "B.Fab")
		)
		(fp_line
			(start -0.120396 0.3048)
			(end -0.120396 0.2794)
			(stroke
				(width 0.1)
				(type default)
			)
			(layer "B.Fab")
		)
		(fp_line
			(start -0.120396 0.2794)
			(end 0.12065 0.2794)
			(stroke
				(width 0.1)
				(type default)
			)
			(layer "B.Fab")
		)
		(fp_line
			(start -0.12065 -0.2794)
			(end -0.12065 -0.3048)
			(stroke
				(width 0.1)
				(type default)
			)
			(layer "B.Fab")
		)
		(fp_line
			(start -0.12065 -0.3048)
			(end -0.67945 -0.3048)
			(stroke
				(width 0.1)
				(type default)
			)
			(layer "B.Fab")
		)
		(fp_line
			(start -0.67945 0.3048)
			(end -0.120396 0.3048)
			(stroke
				(width 0.1)
				(type default)
			)
			(layer "B.Fab")
		)
		(fp_line
			(start -0.67945 -0.3048)
			(end -0.67945 0.3048)
			(stroke
				(width 0.1)
				(type default)
			)
			(layer "B.Fab")
		)
		(pad "1" smd circle
			(at 0.40005 0)
			(size 0 0)
			(layers "B.Cu" "B.Mask" "B.Paste")
			(net "PVDD18_S5_P0")
		)
		(pad "2" smd circle
			(at -0.40005 0)
			(size 0 0)
			(layers "B.Cu" "B.Mask" "B.Paste")
			(net "GND")
		)
	)
	(footprint ""
		(layer "B.Cu")
		(at 182.332376 -116.242846 180)
		(property "Reference" "C1172"
			(at 0 0 0)
			(layer "B.SilkS")
			(hide yes)
			(effects
				(font
					(size 1.27 1.27)
				)
				(justify mirror)
			)
		)
		(property "Value" ""
			(at 0 0 0)
			(layer "B.Fab")
			(effects
				(font
					(size 1.27 1.27)
				)
				(justify mirror)
			)
		)
		(duplicate_pad_numbers_are_jumpers no)
		(fp_line
			(start 0.69215 0.2921)
			(end 0.69215 -0.2921)
			(stroke
				(width 0.1524)
				(type default)
			)
			(layer "B.SilkS")
		)
		(fp_line
			(start 0.69215 -0.2921)
			(end -0.69215 -0.2921)
			(stroke
				(width 0.1524)
				(type default)
			)
			(layer "B.SilkS")
		)
		(fp_line
			(start -0.69215 0.2921)
			(end 0.69215 0.2921)
			(stroke
				(width 0.1524)
				(type default)
			)
			(layer "B.SilkS")
		)
		(fp_line
			(start -0.69215 -0.2921)
			(end -0.69215 0.2921)
			(stroke
				(width 0.1524)
				(type default)
			)
			(layer "B.SilkS")
		)
		(fp_line
			(start 0.51435 0.2794)
			(end 0.51435 -0.2794)
			(stroke
				(width 0.1)
				(type default)
			)
			(layer "B.Fab")
		)
		(fp_line
			(start 0.51435 -0.2794)
			(end -0.51435 -0.2794)
			(stroke
				(width 0.1)
				(type default)
			)
			(layer "B.Fab")
		)
		(fp_line
			(start -0.51435 0.2794)
			(end 0.51435 0.2794)
			(stroke
				(width 0.1)
				(type default)
			)
			(layer "B.Fab")
		)
		(fp_line
			(start -0.51435 -0.2794)
			(end -0.51435 0.2794)
			(stroke
				(width 0.1)
				(type default)
			)
			(layer "B.Fab")
		)
		(pad "1" smd circle
			(at 0.40005 0)
			(size 0 0)
			(layers "B.Cu" "B.Mask" "B.Paste")
			(net "P3V3_AUX")
		)
		(pad "2" smd circle
			(at -0.40005 0)
			(size 0 0)
			(layers "B.Cu" "B.Mask" "B.Paste")
			(net "GND")
		)
		(zone
			(layer "B.Cu")
			(hatch none 0.5)
			(connect_pads
				(clearance 0)
			)
			(min_thickness 0.25)
			(keepout
				(tracks not_allowed)
				(vias allowed)
				(pads allowed)
				(copperpour not_allowed)
				(footprints allowed)
			)
			(placement
				(enabled no)
				(sheetname "")
			)
			(fill
				(thermal_gap 0.5)
				(thermal_bridge_width 0.5)
				(island_removal_mode 0)
			)
			(polygon
				(pts
					(xy 182.141876 -116.154962) (xy 182.141876 -116.330476) (xy 182.233316 -116.388642) (xy 182.432706 -116.388642)
					(xy 182.522876 -116.330476) (xy 182.522876 -116.155216) (xy 182.432706 -116.096796) (xy 182.233316 -116.096796)
				)
			)
		)
	)
	(footprint ""
		(layer "B.Cu")
		(at 319.467484 -335.063084 90)
		(property "Reference" "PC120_3"
			(at 0 0 90)
			(layer "B.SilkS")
			(hide yes)
			(effects
				(font
					(size 1.27 1.27)
				)
				(justify mirror)
			)
		)
		(property "Value" ""
			(at 0 0 90)
			(layer "B.Fab")
			(effects
				(font
					(size 1.27 1.27)
				)
				(justify mirror)
			)
		)
		(duplicate_pad_numbers_are_jumpers no)
		(fp_line
			(start 1.524 -0.762)
			(end -1.524 -0.762)
			(stroke
				(width 0.1524)
				(type default)
			)
			(layer "B.SilkS")
		)
		(fp_line
			(start -1.524 -0.762)
			(end -1.524 0.762)
			(stroke
				(width 0.1524)
				(type default)
			)
			(layer "B.SilkS")
		)
		(fp_line
			(start 1.524 0.762)
			(end 1.524 -0.762)
			(stroke
				(width 0.1524)
				(type default)
			)
			(layer "B.SilkS")
		)
		(fp_line
			(start -1.524 0.762)
			(end 1.524 0.762)
			(stroke
				(width 0.1524)
				(type default)
			)
			(layer "B.SilkS")
		)
		(fp_line
			(start 1.1049 -0.724916)
			(end 1.1049 0.724916)
			(stroke
				(width 0.1)
				(type default)
			)
			(layer "B.Fab")
		)
		(fp_line
			(start -1.1049 -0.724916)
			(end 1.1049 -0.724916)
			(stroke
				(width 0.1)
				(type default)
			)
			(layer "B.Fab")
		)
		(fp_line
			(start 1.1049 0.724916)
			(end -1.1049 0.724916)
			(stroke
				(width 0.1)
				(type default)
			)
			(layer "B.Fab")
		)
		(fp_line
			(start -1.1049 0.724916)
			(end -1.1049 -0.724916)
			(stroke
				(width 0.1)
				(type default)
			)
			(layer "B.Fab")
		)
		(pad "1" smd rect
			(at 0.889 0 90)
			(size 1.016 1.27)
			(layers "B.Cu" "B.Mask" "B.Paste")
			(net "SW_P12V_AUX_PVDDCR_CPU1_P0_FLT")
		)
		(pad "2" smd rect
			(at -0.889 0 90)
			(size 1.016 1.27)
			(layers "B.Cu" "B.Mask" "B.Paste")
			(net "GND")
		)
	)
)
